(kicad_pcb
	(version 20260206)
	(generator "pcbnew")
	(generator_version "10.0")
	(general
		(thickness 1.6)
		(legacy_teardrops no)
	)
	(paper "A4")
	(title_block
		(title "Wiwynn_Tioga_Pass_MB.brd")
		(comment 1 "Tioga Pass / footprints 1915-1920 of 4770")
	)
	(layers
		(0 "F.Cu" signal "TOP")
		(4 "In1.Cu" signal "L2GND")
		(6 "In2.Cu" signal "L3")
		(8 "In3.Cu" signal "L4GND")
		(10 "In4.Cu" signal "L5")
		(12 "In5.Cu" signal "L6GND")
		(14 "In6.Cu" signal "L7VCC")
		(16 "In7.Cu" signal "L8VCC")
		(18 "In8.Cu" signal "L9GND")
		(20 "In9.Cu" signal "L10")
		(22 "In10.Cu" signal "L11GND")
		(24 "In11.Cu" signal "L12")
		(26 "In12.Cu" signal "L13GND")
		(2 "B.Cu" signal "BOTTOM")
		(9 "F.Adhes" user "F.Adhesive")
		(11 "B.Adhes" user "B.Adhesive")
		(13 "F.Paste" user "Package Geometry/Pastemask Top")
		(15 "B.Paste" user "Package Geometry/Pastemask Bottom")
		(5 "F.SilkS" user "Ref Des/Silkscreen Top")
		(7 "B.SilkS" user "Ref Des/Silkscreen Bottom")
		(1 "F.Mask" user "Board Geometry/Soldermask Top")
		(3 "B.Mask" user "Board Geometry/Soldermask Bottom")
		(17 "Dwgs.User" user "User.Drawings")
		(19 "Cmts.User" user "User.Comments")
		(21 "Eco1.User" user "User.Eco1")
		(23 "Eco2.User" user "User.Eco2")
		(25 "Edge.Cuts" user "Board Geometry/Outline")
		(27 "Margin" user)
		(31 "F.CrtYd" user "Package Geometry/Place Bound Top")
		(29 "B.CrtYd" user "Package Geometry/Place Bound Bottom")
		(35 "F.Fab" user "Ref Des/Assembly Top")
		(33 "B.Fab" user "Ref Des/Assembly Bottom")
	)
	(footprint ""
		(layer "F.Cu")
		(at 204.2668 -50.5714)
		(property "Reference" "R4E15"
			(at 0 0 0)
			(layer "F.SilkS")
			(hide yes)
			(effects
				(font
					(size 1.27 1.27)
				)
			)
		)
		(property "Value" ""
			(at 0 0 0)
			(layer "F.Fab")
			(effects
				(font
					(size 1.27 1.27)
				)
			)
		)
		(duplicate_pad_numbers_are_jumpers no)
		(fp_poly
			(pts
				(xy -0.2794 -0.1016) (xy 0.2794 -0.1016) (xy 0.2794 0.9906) (xy -0.2794 0.9906)
			)
			(stroke
				(width 0)
				(type default)
			)
			(fill no)
			(layer "F.CrtYd")
		)
		(fp_line
			(start -0.2794 -0.1016)
			(end -0.2794 0.9906)
			(stroke
				(width 0.1)
				(type default)
			)
			(layer "F.Fab")
		)
		(fp_line
			(start -0.2794 0.9906)
			(end 0.2794 0.9906)
			(stroke
				(width 0.1)
				(type default)
			)
			(layer "F.Fab")
		)
		(fp_line
			(start 0.2794 -0.1016)
			(end -0.2794 -0.1016)
			(stroke
				(width 0.1)
				(type default)
			)
			(layer "F.Fab")
		)
		(fp_line
			(start 0.2794 0.9906)
			(end 0.2794 -0.1016)
			(stroke
				(width 0.1)
				(type default)
			)
			(layer "F.Fab")
		)
		(pad "1" smd rect
			(at 0 0)
			(size 0.508 0.508)
			(layers "F.Cu" "F.Mask" "F.Paste")
			(net "VSENSE_PVCCIN_CPU0_P")
		)
		(pad "2" smd rect
			(at 0 0.889)
			(size 0.508 0.508)
			(layers "F.Cu" "F.Mask" "F.Paste")
			(net "VSENSE_PVCCIN_CPU0_N")
		)
		(zone
			(layer "F.Cu")
			(hatch none 0.5)
			(connect_pads
				(clearance 0)
			)
			(min_thickness 0.25)
			(keepout
				(tracks allowed)
				(vias not_allowed)
				(pads allowed)
				(copperpour not_allowed)
				(footprints allowed)
			)
			(placement
				(enabled no)
				(sheetname "")
			)
			(fill
				(thermal_gap 0.5)
				(thermal_bridge_width 0.5)
				(island_removal_mode 0)
			)
			(polygon
				(pts
					(xy 204.0128 -50.3174) (xy 204.5208 -50.3174) (xy 204.5208 -49.9364) (xy 204.0128 -49.9364)
				)
			)
		)
		(zone
			(layer "F.Cu")
			(hatch none 0.5)
			(connect_pads
				(clearance 0)
			)
			(min_thickness 0.25)
			(keepout
				(tracks not_allowed)
				(vias allowed)
				(pads allowed)
				(copperpour not_allowed)
				(footprints allowed)
			)
			(placement
				(enabled no)
				(sheetname "")
			)
			(fill
				(thermal_gap 0.5)
				(thermal_bridge_width 0.5)
				(island_removal_mode 0)
			)
			(polygon
				(pts
					(xy 204.0128 -49.9364) (xy 204.5208 -49.9364) (xy 204.5208 -50.3174) (xy 204.0128 -50.3174)
				)
			)
		)
	)
	(footprint ""
		(layer "F.Cu")
		(at 436.499 -19.3675)
		(property "Reference" "C10W3"
			(at -0.8382 -0.67818 0)
			(unlocked yes)
			(layer "F.SilkS")
			(effects
				(font
					(size 0.4064 0.254)
					(thickness 0.1524)
				)
				(justify left)
			)
		)
		(property "Value" ""
			(at 0 0 0)
			(layer "F.Fab")
			(effects
				(font
					(size 1.27 1.27)
				)
			)
		)
		(duplicate_pad_numbers_are_jumpers no)
		(fp_poly
			(pts
				(xy 0.3048 -0.1016) (xy 0.3048 0.9906) (xy -0.3048 0.9906) (xy -0.3048 -0.1016)
			)
			(stroke
				(width 0)
				(type default)
			)
			(fill no)
			(layer "F.CrtYd")
		)
		(fp_line
			(start -0.3048 -0.1016)
			(end -0.3048 0.9906)
			(stroke
				(width 0.1)
				(type default)
			)
			(layer "F.Fab")
		)
		(fp_line
			(start -0.3048 0.9906)
			(end 0.3048 0.9906)
			(stroke
				(width 0.1)
				(type default)
			)
			(layer "F.Fab")
		)
		(fp_line
			(start 0.3048 -0.1016)
			(end -0.3048 -0.1016)
			(stroke
				(width 0.1)
				(type default)
			)
			(layer "F.Fab")
		)
		(fp_line
			(start 0.3048 0.9906)
			(end 0.3048 -0.1016)
			(stroke
				(width 0.1)
				(type default)
			)
			(layer "F.Fab")
		)
		(pad "1" smd rect
			(at 0 0)
			(size 0.508 0.508)
			(layers "F.Cu" "F.Mask" "F.Paste")
			(net "PUMP_TACH0")
		)
		(pad "2" smd rect
			(at 0 0.889)
			(size 0.508 0.508)
			(layers "F.Cu" "F.Mask" "F.Paste")
			(net "GND")
		)
		(zone
			(layer "F.Cu")
			(hatch none 0.5)
			(connect_pads
				(clearance 0)
			)
			(min_thickness 0.25)
			(keepout
				(tracks allowed)
				(vias not_allowed)
				(pads allowed)
				(copperpour not_allowed)
				(footprints allowed)
			)
			(placement
				(enabled no)
				(sheetname "")
			)
			(fill
				(thermal_gap 0.5)
				(thermal_bridge_width 0.5)
				(island_removal_mode 0)
			)
			(polygon
				(pts
					(xy 436.245 -19.1135) (xy 436.753 -19.1135) (xy 436.753 -18.7325) (xy 436.245 -18.7325)
				)
			)
		)
		(zone
			(layer "F.Cu")
			(hatch none 0.5)
			(connect_pads
				(clearance 0)
			)
			(min_thickness 0.25)
			(keepout
				(tracks not_allowed)
				(vias allowed)
				(pads allowed)
				(copperpour not_allowed)
				(footprints allowed)
			)
			(placement
				(enabled no)
				(sheetname "")
			)
			(fill
				(thermal_gap 0.5)
				(thermal_bridge_width 0.5)
				(island_removal_mode 0)
			)
			(polygon
				(pts
					(xy 436.245 -18.7325) (xy 436.753 -18.7325) (xy 436.753 -19.1135) (xy 436.245 -19.1135)
				)
			)
		)
	)
	(footprint ""
		(layer "F.Cu")
		(at 173.8757 -126.99238 -90)
		(property "Reference" "Q4B1"
			(at 2.27838 2.98323 90)
			(unlocked yes)
			(layer "F.SilkS")
			(effects
				(font
					(size 0.7874 0.5842)
					(thickness 0.1524)
				)
				(justify left)
			)
		)
		(property "Value" ""
			(at 0 0 270)
			(layer "F.Fab")
			(effects
				(font
					(size 1.27 1.27)
				)
			)
		)
		(duplicate_pad_numbers_are_jumpers no)
		(fp_circle
			(center -0.508 -0.7874)
			(end -0.508 -0.9144)
			(stroke
				(width 0.254)
				(type default)
			)
			(fill no)
			(layer "F.SilkS")
		)
		(fp_poly
			(pts
				(xy 0.2159 1.7526) (xy 1.5621 1.7526) (xy 1.5621 -0.4572) (xy 0.2159 -0.4572)
			)
			(stroke
				(width 0)
				(type default)
			)
			(fill no)
			(layer "F.CrtYd")
		)
		(fp_line
			(start 0.2159 1.75514)
			(end 1.5621 1.75514)
			(stroke
				(width 0.1)
				(type default)
			)
			(layer "F.Fab")
		)
		(fp_line
			(start 1.5621 1.75514)
			(end 1.5621 -0.45466)
			(stroke
				(width 0.1)
				(type default)
			)
			(layer "F.Fab")
		)
		(fp_line
			(start 0.2159 -0.45466)
			(end 0.2159 1.75514)
			(stroke
				(width 0.1)
				(type default)
			)
			(layer "F.Fab")
		)
		(fp_line
			(start 1.5621 -0.45466)
			(end 0.2159 -0.45466)
			(stroke
				(width 0.1)
				(type default)
			)
			(layer "F.Fab")
		)
		(fp_circle
			(center -0.508 -0.7874)
			(end -0.508 -0.9144)
			(stroke
				(width 0.254)
				(type default)
			)
			(fill no)
			(layer "F.Fab")
		)
		(pad "1" smd rect
			(at 0 0 270)
			(size 1.016 0.381)
			(layers "F.Cu" "F.Mask" "F.Paste")
			(net "GND")
		)
		(pad "2" smd rect
			(at 0 0.65024 270)
			(size 1.016 0.381)
			(layers "F.Cu" "F.Mask" "F.Paste")
			(net "IRQ_PVDDQ_KLM_VRHOT_LVT3_N")
		)
		(pad "3" smd rect
			(at 0 1.30048 270)
			(size 1.016 0.381)
			(layers "F.Cu" "F.Mask" "F.Paste")
			(net "H_CPU1_MEMKLM_MEMHOT_G_N")
		)
		(pad "4" smd rect
			(at 1.778 1.30048 270)
			(size 1.016 0.381)
			(layers "F.Cu" "F.Mask" "F.Paste")
			(net "GND")
		)
		(pad "5" smd rect
			(at 1.778 0.65024 270)
			(size 1.016 0.381)
			(layers "F.Cu" "F.Mask" "F.Paste")
			(net "H_CPU1_MEMKLM_MEMHOT")
		)
		(pad "6" smd rect
			(at 1.778 0 270)
			(size 1.016 0.381)
			(layers "F.Cu" "F.Mask" "F.Paste")
			(net "H_CPU1_MEMKLM_MEMHOT")
		)
		(zone
			(layer "F.Cu")
			(hatch none 0.5)
			(connect_pads
				(clearance 0)
			)
			(min_thickness 0.25)
			(keepout
				(tracks allowed)
				(vias not_allowed)
				(pads allowed)
				(copperpour not_allowed)
				(footprints allowed)
			)
			(placement
				(enabled no)
				(sheetname "")
			)
			(fill
				(thermal_gap 0.5)
				(thermal_bridge_width 0.5)
				(island_removal_mode 0)
			)
			(polygon
				(pts
					(xy 174.0662 -127.50038) (xy 174.0662 -126.48438) (xy 172.3771 -126.48438) (xy 172.3771 -127.50038)
				)
			)
		)
		(zone
			(layer "F.Cu")
			(hatch none 0.5)
			(connect_pads
				(clearance 0)
			)
			(min_thickness 0.25)
			(keepout
				(tracks allowed)
				(vias not_allowed)
				(pads allowed)
				(copperpour not_allowed)
				(footprints allowed)
			)
			(placement
				(enabled no)
				(sheetname "")
			)
			(fill
				(thermal_gap 0.5)
				(thermal_bridge_width 0.5)
				(island_removal_mode 0)
			)
			(polygon
				(pts
					(xy 174.0662 -125.72238) (xy 174.0662 -124.70638) (xy 172.3771 -124.70638) (xy 172.3771 -125.72238)
				)
			)
		)
	)
	(footprint ""
		(layer "F.Cu")
		(at 479.77298 -35.5854 90)
		(property "Reference" "R1W25"
			(at -0.8382 -0.67818 90)
			(unlocked yes)
			(layer "F.SilkS")
			(effects
				(font
					(size 0.4064 0.254)
					(thickness 0.1524)
				)
				(justify left)
			)
		)
		(property "Value" ""
			(at 0 0 90)
			(layer "F.Fab")
			(effects
				(font
					(size 1.27 1.27)
				)
			)
		)
		(duplicate_pad_numbers_are_jumpers no)
		(fp_poly
			(pts
				(xy -0.2794 -0.1016) (xy 0.2794 -0.1016) (xy 0.2794 0.9906) (xy -0.2794 0.9906)
			)
			(stroke
				(width 0)
				(type default)
			)
			(fill no)
			(layer "F.CrtYd")
		)
		(fp_line
			(start 0.2794 -0.1016)
			(end -0.2794 -0.1016)
			(stroke
				(width 0.1)
				(type default)
			)
			(layer "F.Fab")
		)
		(fp_line
			(start -0.2794 -0.1016)
			(end -0.2794 0.9906)
			(stroke
				(width 0.1)
				(type default)
			)
			(layer "F.Fab")
		)
		(fp_line
			(start 0.2794 0.9906)
			(end 0.2794 -0.1016)
			(stroke
				(width 0.1)
				(type default)
			)
			(layer "F.Fab")
		)
		(fp_line
			(start -0.2794 0.9906)
			(end 0.2794 0.9906)
			(stroke
				(width 0.1)
				(type default)
			)
			(layer "F.Fab")
		)
		(pad "1" smd rect
			(at 0 0 90)
			(size 0.508 0.508)
			(layers "F.Cu" "F.Mask" "F.Paste")
			(net "PU_33P_33M_SMBADR")
		)
		(pad "2" smd rect
			(at 0 0.889 90)
			(size 0.508 0.508)
			(layers "F.Cu" "F.Mask" "F.Paste")
			(net "GND")
		)
		(zone
			(layer "F.Cu")
			(hatch none 0.5)
			(connect_pads
				(clearance 0)
			)
			(min_thickness 0.25)
			(keepout
				(tracks allowed)
				(vias not_allowed)
				(pads allowed)
				(copperpour not_allowed)
				(footprints allowed)
			)
			(placement
				(enabled no)
				(sheetname "")
			)
			(fill
				(thermal_gap 0.5)
				(thermal_bridge_width 0.5)
				(island_removal_mode 0)
			)
			(polygon
				(pts
					(xy 480.02698 -35.3314) (xy 480.02698 -35.8394) (xy 480.40798 -35.8394) (xy 480.40798 -35.3314)
				)
			)
		)
		(zone
			(layer "F.Cu")
			(hatch none 0.5)
			(connect_pads
				(clearance 0)
			)
			(min_thickness 0.25)
			(keepout
				(tracks not_allowed)
				(vias allowed)
				(pads allowed)
				(copperpour not_allowed)
				(footprints allowed)
			)
			(placement
				(enabled no)
				(sheetname "")
			)
			(fill
				(thermal_gap 0.5)
				(thermal_bridge_width 0.5)
				(island_removal_mode 0)
			)
			(polygon
				(pts
					(xy 480.40798 -35.3314) (xy 480.40798 -35.8394) (xy 480.02698 -35.8394) (xy 480.02698 -35.3314)
				)
			)
		)
	)
	(footprint ""
		(layer "F.Cu")
		(at 352.363532 12.003278 -90)
		(property "Reference" "T1P19"
			(at 0 0 270)
			(layer "F.SilkS")
			(hide yes)
			(effects
				(font
					(size 1.27 1.27)
				)
			)
		)
		(property "Value" "*"
			(at -3.302 1.12395 270)
			(unlocked yes)
			(layer "F.Fab")
			(hide yes)
			(effects
				(font
					(size 0.889 0.889)
					(thickness 0.1524)
				)
			)
		)
		(property "Device Type" "TPAD-DIFF-4P-GP_DISCRET-GB3-TPA"
			(at -3.302 -0.40005 270)
			(unlocked yes)
			(layer "F.Fab")
			(hide yes)
			(effects
				(font
					(size 0.889 0.889)
					(thickness 0.1524)
				)
			)
		)
		(duplicate_pad_numbers_are_jumpers no)
		(fp_line
			(start -2.286 2.286)
			(end 2.286 2.286)
			(stroke
				(width 0.1524)
				(type default)
			)
			(layer "F.SilkS")
		)
		(fp_line
			(start 2.286 2.286)
			(end 2.286 -2.286)
			(stroke
				(width 0.1524)
				(type default)
			)
			(layer "F.SilkS")
		)
		(fp_line
			(start -2.286 -2.286)
			(end -2.286 2.286)
			(stroke
				(width 0.1524)
				(type default)
			)
			(layer "F.SilkS")
		)
		(fp_line
			(start 2.286 -2.286)
			(end -2.286 -2.286)
			(stroke
				(width 0.1524)
				(type default)
			)
			(layer "F.SilkS")
		)
		(fp_line
			(start -2.413 -2.413)
			(end -2.413 -1.143)
			(stroke
				(width 0.4064)
				(type default)
			)
			(layer "F.SilkS")
		)
		(fp_line
			(start -1.143 -2.413)
			(end -2.413 -2.413)
			(stroke
				(width 0.4064)
				(type default)
			)
			(layer "F.SilkS")
		)
		(fp_rect
			(start -2.54 2.54)
			(end 2.54 -2.54)
			(stroke
				(width 0)
				(type default)
			)
			(fill no)
			(layer "F.CrtYd")
		)
		(fp_rect
			(start -2.54 2.54)
			(end 2.54 -2.54)
			(stroke
				(width 0)
				(type default)
			)
			(fill no)
			(layer "F.Fab")
		)
		(pad "1" thru_hole circle
			(at -1.27 -1.27 270)
			(size 1.524 1.524)
			(drill 0.9144)
			(layers "*.Cu" "*.Mask")
			(remove_unused_layers no)
			(net "L1_100OHM_6INCH_DP")
			(clearance -0.0508)
			(thermal_gap 0.127)
			(padstack
				(mode front_inner_back)
				(layer "Inner"
					(shape circle)
					(size 1.1684 1.1684)
					(clearance 0.127)
				)
				(layer "B.Cu"
					(shape circle)
					(size 1.524 1.524)
					(clearance -0.0508)
				)
			)
		)
		(pad "2" thru_hole circle
			(at 1.27 -1.27 270)
			(size 1.524 1.524)
			(drill 0.9144)
			(layers "*.Cu" "*.Mask")
			(remove_unused_layers no)
			(net "L1_100OHM_6INCH_DN")
			(clearance -0.0508)
			(thermal_gap 0.127)
			(padstack
				(mode front_inner_back)
				(layer "Inner"
					(shape circle)
					(size 1.1684 1.1684)
					(clearance 0.127)
				)
				(layer "B.Cu"
					(shape circle)
					(size 1.524 1.524)
					(clearance -0.0508)
				)
			)
		)
		(pad "GND1" thru_hole rect
			(at -1.27 1.27 270)
			(size 1.524 1.524)
			(drill 0.9144)
			(layers "*.Cu" "*.Mask")
			(remove_unused_layers no)
			(net "GND")
			(clearance -0.0508)
			(thermal_gap 0.127)
			(padstack
				(mode front_inner_back)
				(layer "Inner"
					(shape circle)
					(size 1.1684 1.1684)
					(clearance 0.127)
				)
				(layer "B.Cu"
					(shape rect)
					(size 1.524 1.524)
					(clearance -0.0508)
				)
			)
		)
		(pad "GND2" thru_hole rect
			(at 1.27 1.27 270)
			(size 1.524 1.524)
			(drill 0.9144)
			(layers "*.Cu" "*.Mask")
			(remove_unused_layers no)
			(net "GND")
			(clearance -0.0508)
			(thermal_gap 0.127)
			(padstack
				(mode front_inner_back)
				(layer "Inner"
					(shape circle)
					(size 1.1684 1.1684)
					(clearance 0.127)
				)
				(layer "B.Cu"
					(shape rect)
					(size 1.524 1.524)
					(clearance -0.0508)
				)
			)
		)
	)
	(footprint ""
		(layer "F.Cu")
		(at 411.0355 -108.966 -90)
		(property "Reference" "R2N8"
			(at 0 0 270)
			(layer "F.SilkS")
			(hide yes)
			(effects
				(font
					(size 1.27 1.27)
				)
			)
		)
		(property "Value" ""
			(at 0 0 270)
			(layer "F.Fab")
			(effects
				(font
					(size 1.27 1.27)
				)
			)
		)
		(duplicate_pad_numbers_are_jumpers no)
		(fp_poly
			(pts
				(xy -0.2794 -0.1016) (xy 0.2794 -0.1016) (xy 0.2794 0.9906) (xy -0.2794 0.9906)
			)
			(stroke
				(width 0)
				(type default)
			)
			(fill no)
			(layer "F.CrtYd")
		)
		(fp_line
			(start -0.2794 0.9906)
			(end 0.2794 0.9906)
			(stroke
				(width 0.1)
				(type default)
			)
			(layer "F.Fab")
		)
		(fp_line
			(start 0.2794 0.9906)
			(end 0.2794 -0.1016)
			(stroke
				(width 0.1)
				(type default)
			)
			(layer "F.Fab")
		)
		(fp_line
			(start -0.2794 -0.1016)
			(end -0.2794 0.9906)
			(stroke
				(width 0.1)
				(type default)
			)
			(layer "F.Fab")
		)
		(fp_line
			(start 0.2794 -0.1016)
			(end -0.2794 -0.1016)
			(stroke
				(width 0.1)
				(type default)
			)
			(layer "F.Fab")
		)
		(pad "1" smd rect
			(at 0 0 270)
			(size 0.508 0.508)
			(layers "F.Cu" "F.Mask" "F.Paste")
			(net "P3V3_STBY")
		)
		(pad "2" smd rect
			(at 0 0.889 270)
			(size 0.508 0.508)
			(layers "F.Cu" "F.Mask" "F.Paste")
			(net "SMB_SMLINK0_STBY_LVC3_SDA")
		)
		(zone
			(layer "F.Cu")
			(hatch none 0.5)
			(connect_pads
				(clearance 0)
			)
			(min_thickness 0.25)
			(keepout
				(tracks not_allowed)
				(vias allowed)
				(pads allowed)
				(copperpour not_allowed)
				(footprints allowed)
			)
			(placement
				(enabled no)
				(sheetname "")
			)
			(fill
				(thermal_gap 0.5)
				(thermal_bridge_width 0.5)
				(island_removal_mode 0)
			)
			(polygon
				(pts
					(xy 410.4005 -109.22) (xy 410.4005 -108.712) (xy 410.7815 -108.712) (xy 410.7815 -109.22)
				)
			)
		)
		(zone
			(layer "F.Cu")
			(hatch none 0.5)
			(connect_pads
				(clearance 0)
			)
			(min_thickness 0.25)
			(keepout
				(tracks allowed)
				(vias not_allowed)
				(pads allowed)
				(copperpour not_allowed)
				(footprints allowed)
			)
			(placement
				(enabled no)
				(sheetname "")
			)
			(fill
				(thermal_gap 0.5)
				(thermal_bridge_width 0.5)
				(island_removal_mode 0)
			)
			(polygon
				(pts
					(xy 410.7815 -109.22) (xy 410.7815 -108.712) (xy 410.4005 -108.712) (xy 410.4005 -109.22)
				)
			)
		)
	)
)
